(kicad_pcb
	(version 20260206)
	(generator "pcbnew")
	(generator_version "10.0")
	(general
		(thickness 1.6)
		(legacy_teardrops no)
	)
	(paper "A4")
	(title_block
		(title "peb — Lightning_PEB_BRD.brd")
		(comment 1 "Lightning (Wiwynn / Facebook NVMe JBOF) / footprints 1467-1474 of 2563")
	)
	(layers
		(0 "F.Cu" signal "TOP")
		(4 "In1.Cu" signal "L2GND")
		(6 "In2.Cu" signal "L3")
		(8 "In3.Cu" signal "L4VCC")
		(10 "In4.Cu" signal "L5VCC")
		(12 "In5.Cu" signal "L6")
		(14 "In6.Cu" signal "L7GND")
		(2 "B.Cu" signal "BOTTOM")
		(9 "F.Adhes" user "F.Adhesive")
		(11 "B.Adhes" user "B.Adhesive")
		(13 "F.Paste" user "Package Geometry/Pastemask Top")
		(15 "B.Paste" user "Package Geometry/Pastemask Bottom")
		(5 "F.SilkS" user "Ref Des/Silkscreen Top")
		(7 "B.SilkS" user "Ref Des/Silkscreen Bottom")
		(1 "F.Mask" user "Board Geometry/Soldermask Top")
		(3 "B.Mask" user "Board Geometry/Soldermask Bottom")
		(17 "Dwgs.User" user "User.Drawings")
		(19 "Cmts.User" user "User.Comments")
		(21 "Eco1.User" user "User.Eco1")
		(23 "Eco2.User" user "User.Eco2")
		(25 "Edge.Cuts" user "Board Geometry/Outline")
		(27 "Margin" user)
		(31 "F.CrtYd" user "Package Geometry/Place Bound Top")
		(29 "B.CrtYd" user "Package Geometry/Place Bound Bottom")
		(35 "F.Fab" user "Ref Des/Assembly Top")
		(33 "B.Fab" user "Ref Des/Assembly Bottom")
	)
	(footprint ""
		(layer "F.Cu")
		(at 7.597648 -77.895196 90)
		(property "Reference" "R398"
			(at 0 0 90)
			(layer "F.SilkS")
			(hide yes)
			(effects
				(font
					(size 1.27 1.27)
				)
			)
		)
		(property "Value" "10KR2F-2-GP"
			(at 0.064008 -3.993896 90)
			(unlocked yes)
			(layer "F.Fab")
			(hide yes)
			(effects
				(font
					(size 1.016 1.016)
					(thickness 0.1524)
				)
			)
		)
		(property "Device Type" "R402H16"
			(at 0.064008 -5.517896 90)
			(unlocked yes)
			(layer "F.Fab")
			(hide yes)
			(effects
				(font
					(size 1.016 1.016)
					(thickness 0.1524)
				)
			)
		)
		(duplicate_pad_numbers_are_jumpers no)
		(fp_line
			(start 0.508 -0.9398)
			(end -0.508 -0.9398)
			(stroke
				(width 0.1524)
				(type default)
			)
			(layer "F.SilkS")
		)
		(fp_line
			(start -0.508 -0.9398)
			(end -0.508 0.9398)
			(stroke
				(width 0.1524)
				(type default)
			)
			(layer "F.SilkS")
		)
		(fp_rect
			(start -0.508 0.9398)
			(end 0.508 -0.9398)
			(stroke
				(width 0)
				(type default)
			)
			(fill no)
			(layer "F.CrtYd")
		)
		(fp_rect
			(start -0.508 0.9398)
			(end 0.508 -0.9398)
			(stroke
				(width 0)
				(type default)
			)
			(fill no)
			(layer "F.Fab")
		)
		(pad "1" smd custom
			(at 0 -0.4445 90)
			(size 0.1397 0.1397)
			(layers "F.Cu" "F.Mask" "F.Paste")
			(net "P3V3_STBY")
			(options
				(clearance outline)
				(anchor circle)
			)
			(primitives
				(gr_poly
					(pts
						(arc
							(start -0.1778 -0.2794)
							(mid -0.249642 -0.249642)
							(end -0.2794 -0.1778)
						)
						(arc
							(start -0.2794 0.1778)
							(mid -0.249642 0.249642)
							(end -0.1778 0.2794)
						)
						(arc
							(start 0.1778 0.2794)
							(mid 0.249642 0.249642)
							(end 0.2794 0.1778)
						)
						(arc
							(start 0.2794 -0.1778)
							(mid 0.249642 -0.249642)
							(end 0.1778 -0.2794)
						)
					)
					(width 0)
					(fill yes)
				)
			)
		)
		(pad "2" smd custom
			(at 0 0.4445 90)
			(size 0.1397 0.1397)
			(layers "F.Cu" "F.Mask" "F.Paste")
			(net "LAN_SMB_DAT")
			(options
				(clearance outline)
				(anchor circle)
			)
			(primitives
				(gr_poly
					(pts
						(arc
							(start -0.1778 -0.2794)
							(mid -0.249642 -0.249642)
							(end -0.2794 -0.1778)
						)
						(arc
							(start -0.2794 0.1778)
							(mid -0.249642 0.249642)
							(end -0.1778 0.2794)
						)
						(arc
							(start 0.1778 0.2794)
							(mid 0.249642 0.249642)
							(end 0.2794 0.1778)
						)
						(arc
							(start 0.2794 -0.1778)
							(mid 0.249642 -0.249642)
							(end 0.1778 -0.2794)
						)
					)
					(width 0)
					(fill yes)
				)
			)
		)
	)
	(footprint ""
		(layer "F.Cu")
		(at 145.761202 -64.416432 -90)
		(property "Reference" "PC198"
			(at 0 0 270)
			(layer "F.SilkS")
			(hide yes)
			(effects
				(font
					(size 1.27 1.27)
				)
			)
		)
		(property "Value" "SC10U25V5KX-GP"
			(at -0.0762 -6.1214 270)
			(unlocked yes)
			(layer "F.Fab")
			(hide yes)
			(effects
				(font
					(size 1.016 1.016)
					(thickness 0.1524)
				)
			)
		)
		(property "Device Type" "C805H56"
			(at -0.0762 -8.1534 270)
			(unlocked yes)
			(layer "F.Fab")
			(hide yes)
			(effects
				(font
					(size 1.016 1.016)
					(thickness 0.1524)
				)
			)
		)
		(duplicate_pad_numbers_are_jumpers no)
		(fp_line
			(start 0.635 0)
			(end -0.635 0)
			(stroke
				(width 0.508)
				(type default)
			)
			(layer "F.SilkS")
		)
		(fp_rect
			(start -0.9652 1.778)
			(end 0.9652 -1.778)
			(stroke
				(width 0)
				(type default)
			)
			(fill no)
			(layer "F.CrtYd")
		)
		(fp_poly
			(pts
				(xy -0.9652 -1.778) (xy 0.9652 -1.778) (xy 0.9652 1.778) (xy -0.9652 1.778)
			)
			(stroke
				(width 0)
				(type default)
			)
			(fill no)
			(layer "F.Fab")
		)
		(pad "1" smd rect
			(at 0 -0.9652 270)
			(size 1.397 1.143)
			(layers "F.Cu" "F.Mask" "F.Paste")
			(net "P0V9_VIN")
		)
		(pad "2" smd rect
			(at 0 0.9652 270)
			(size 1.397 1.143)
			(layers "F.Cu" "F.Mask" "F.Paste")
			(net "GND")
		)
	)
	(footprint ""
		(layer "F.Cu")
		(at 73.914 -195.6816 180)
		(property "Reference" "R7961"
			(at 0 0 180)
			(layer "F.SilkS")
			(hide yes)
			(effects
				(font
					(size 1.27 1.27)
				)
			)
		)
		(property "Value" "0R2J-2-GP"
			(at 0.064008 -3.993896 180)
			(unlocked yes)
			(layer "F.Fab")
			(hide yes)
			(effects
				(font
					(size 1.016 1.016)
					(thickness 0.1524)
				)
			)
		)
		(property "Device Type" "R402H16"
			(at 0.064008 -5.517896 180)
			(unlocked yes)
			(layer "F.Fab")
			(hide yes)
			(effects
				(font
					(size 1.016 1.016)
					(thickness 0.1524)
				)
			)
		)
		(duplicate_pad_numbers_are_jumpers no)
		(fp_line
			(start 0.508 -0.9398)
			(end -0.508 -0.9398)
			(stroke
				(width 0.1524)
				(type default)
			)
			(layer "F.SilkS")
		)
		(fp_line
			(start -0.508 -0.9398)
			(end -0.508 0.9398)
			(stroke
				(width 0.1524)
				(type default)
			)
			(layer "F.SilkS")
		)
		(fp_rect
			(start -0.508 0.9398)
			(end 0.508 -0.9398)
			(stroke
				(width 0)
				(type default)
			)
			(fill no)
			(layer "F.CrtYd")
		)
		(fp_rect
			(start -0.508 0.9398)
			(end 0.508 -0.9398)
			(stroke
				(width 0)
				(type default)
			)
			(fill no)
			(layer "F.Fab")
		)
		(pad "1" smd custom
			(at 0 -0.4445 180)
			(size 0.1397 0.1397)
			(layers "F.Cu" "F.Mask" "F.Paste")
			(net "SSD_PWREN11")
			(options
				(clearance outline)
				(anchor circle)
			)
			(primitives
				(gr_poly
					(pts
						(arc
							(start -0.1778 -0.2794)
							(mid -0.249642 -0.249642)
							(end -0.2794 -0.1778)
						)
						(arc
							(start -0.2794 0.1778)
							(mid -0.249642 0.249642)
							(end -0.1778 0.2794)
						)
						(arc
							(start 0.1778 0.2794)
							(mid 0.249642 0.249642)
							(end 0.2794 0.1778)
						)
						(arc
							(start 0.2794 -0.1778)
							(mid 0.249642 -0.249642)
							(end 0.1778 -0.2794)
						)
					)
					(width 0)
					(fill yes)
				)
			)
		)
		(pad "2" smd custom
			(at 0 0.4445 180)
			(size 0.1397 0.1397)
			(layers "F.Cu" "F.Mask" "F.Paste")
			(net "SSD_PWREN11_R")
			(options
				(clearance outline)
				(anchor circle)
			)
			(primitives
				(gr_poly
					(pts
						(arc
							(start -0.1778 -0.2794)
							(mid -0.249642 -0.249642)
							(end -0.2794 -0.1778)
						)
						(arc
							(start -0.2794 0.1778)
							(mid -0.249642 0.249642)
							(end -0.1778 0.2794)
						)
						(arc
							(start 0.1778 0.2794)
							(mid 0.249642 0.249642)
							(end 0.2794 0.1778)
						)
						(arc
							(start 0.2794 -0.1778)
							(mid 0.249642 -0.249642)
							(end 0.1778 -0.2794)
						)
					)
					(width 0)
					(fill yes)
				)
			)
		)
	)
	(footprint ""
		(layer "F.Cu")
		(at 22.4536 -52.2224 180)
		(property "Reference" "R560"
			(at 0 0 180)
			(layer "F.SilkS")
			(hide yes)
			(effects
				(font
					(size 1.27 1.27)
				)
			)
		)
		(property "Value" "0R2J-2-GP"
			(at 0.064008 -3.993896 180)
			(unlocked yes)
			(layer "F.Fab")
			(hide yes)
			(effects
				(font
					(size 1.016 1.016)
					(thickness 0.1524)
				)
			)
		)
		(property "Device Type" "R402H16"
			(at 0.064008 -5.517896 180)
			(unlocked yes)
			(layer "F.Fab")
			(hide yes)
			(effects
				(font
					(size 1.016 1.016)
					(thickness 0.1524)
				)
			)
		)
		(duplicate_pad_numbers_are_jumpers no)
		(fp_line
			(start 0.508 -0.9398)
			(end -0.508 -0.9398)
			(stroke
				(width 0.1524)
				(type default)
			)
			(layer "F.SilkS")
		)
		(fp_line
			(start -0.508 -0.9398)
			(end -0.508 0.9398)
			(stroke
				(width 0.1524)
				(type default)
			)
			(layer "F.SilkS")
		)
		(fp_rect
			(start -0.508 0.9398)
			(end 0.508 -0.9398)
			(stroke
				(width 0)
				(type default)
			)
			(fill no)
			(layer "F.CrtYd")
		)
		(fp_rect
			(start -0.508 0.9398)
			(end 0.508 -0.9398)
			(stroke
				(width 0)
				(type default)
			)
			(fill no)
			(layer "F.Fab")
		)
		(pad "1" smd custom
			(at 0 -0.4445 180)
			(size 0.1397 0.1397)
			(layers "F.Cu" "F.Mask" "F.Paste")
			(net "NIC0_MDI0_N3_R")
			(options
				(clearance outline)
				(anchor circle)
			)
			(primitives
				(gr_poly
					(pts
						(arc
							(start -0.1778 -0.2794)
							(mid -0.249642 -0.249642)
							(end -0.2794 -0.1778)
						)
						(arc
							(start -0.2794 0.1778)
							(mid -0.249642 0.249642)
							(end -0.1778 0.2794)
						)
						(arc
							(start 0.1778 0.2794)
							(mid 0.249642 0.249642)
							(end 0.2794 0.1778)
						)
						(arc
							(start 0.2794 -0.1778)
							(mid 0.249642 -0.249642)
							(end 0.1778 -0.2794)
						)
					)
					(width 0)
					(fill yes)
				)
			)
		)
		(pad "2" smd custom
			(at 0 0.4445 180)
			(size 0.1397 0.1397)
			(layers "F.Cu" "F.Mask" "F.Paste")
			(net "NIC0_MDI0_N3")
			(options
				(clearance outline)
				(anchor circle)
			)
			(primitives
				(gr_poly
					(pts
						(arc
							(start -0.1778 -0.2794)
							(mid -0.249642 -0.249642)
							(end -0.2794 -0.1778)
						)
						(arc
							(start -0.2794 0.1778)
							(mid -0.249642 0.249642)
							(end -0.1778 0.2794)
						)
						(arc
							(start 0.1778 0.2794)
							(mid 0.249642 0.249642)
							(end 0.2794 0.1778)
						)
						(arc
							(start 0.2794 -0.1778)
							(mid 0.249642 -0.249642)
							(end 0.1778 -0.2794)
						)
					)
					(width 0)
					(fill yes)
				)
			)
		)
	)
	(footprint ""
		(layer "F.Cu")
		(at 271.966182 -10.902442 180)
		(property "Reference" "R215"
			(at 0 0 180)
			(layer "F.SilkS")
			(hide yes)
			(effects
				(font
					(size 1.27 1.27)
				)
			)
		)
		(property "Value" "4K7R2F-GP"
			(at 0.064008 -3.993896 180)
			(unlocked yes)
			(layer "F.Fab")
			(hide yes)
			(effects
				(font
					(size 1.016 1.016)
					(thickness 0.1524)
				)
			)
		)
		(property "Device Type" "R402H16"
			(at 0.064008 -5.517896 180)
			(unlocked yes)
			(layer "F.Fab")
			(hide yes)
			(effects
				(font
					(size 1.016 1.016)
					(thickness 0.1524)
				)
			)
		)
		(duplicate_pad_numbers_are_jumpers no)
		(fp_line
			(start 0.508 -0.9398)
			(end -0.508 -0.9398)
			(stroke
				(width 0.1524)
				(type default)
			)
			(layer "F.SilkS")
		)
		(fp_line
			(start -0.508 -0.9398)
			(end -0.508 0.9398)
			(stroke
				(width 0.1524)
				(type default)
			)
			(layer "F.SilkS")
		)
		(fp_rect
			(start -0.508 0.9398)
			(end 0.508 -0.9398)
			(stroke
				(width 0)
				(type default)
			)
			(fill no)
			(layer "F.CrtYd")
		)
		(fp_rect
			(start -0.508 0.9398)
			(end 0.508 -0.9398)
			(stroke
				(width 0)
				(type default)
			)
			(fill no)
			(layer "F.Fab")
		)
		(pad "1" smd custom
			(at 0 -0.4445 180)
			(size 0.1397 0.1397)
			(layers "F.Cu" "F.Mask" "F.Paste")
			(net "CLK_P_5_R")
			(options
				(clearance outline)
				(anchor circle)
			)
			(primitives
				(gr_poly
					(pts
						(arc
							(start -0.1778 -0.2794)
							(mid -0.249642 -0.249642)
							(end -0.2794 -0.1778)
						)
						(arc
							(start -0.2794 0.1778)
							(mid -0.249642 0.249642)
							(end -0.1778 0.2794)
						)
						(arc
							(start 0.1778 0.2794)
							(mid 0.249642 0.249642)
							(end 0.2794 0.1778)
						)
						(arc
							(start 0.2794 -0.1778)
							(mid 0.249642 -0.249642)
							(end 0.1778 -0.2794)
						)
					)
					(width 0)
					(fill yes)
				)
			)
		)
		(pad "2" smd custom
			(at 0 0.4445 180)
			(size 0.1397 0.1397)
			(layers "F.Cu" "F.Mask" "F.Paste")
			(net "GND")
			(options
				(clearance outline)
				(anchor circle)
			)
			(primitives
				(gr_poly
					(pts
						(arc
							(start -0.1778 -0.2794)
							(mid -0.249642 -0.249642)
							(end -0.2794 -0.1778)
						)
						(arc
							(start -0.2794 0.1778)
							(mid -0.249642 0.249642)
							(end -0.1778 0.2794)
						)
						(arc
							(start 0.1778 0.2794)
							(mid 0.249642 0.249642)
							(end 0.2794 0.1778)
						)
						(arc
							(start 0.2794 -0.1778)
							(mid 0.249642 -0.249642)
							(end 0.1778 -0.2794)
						)
					)
					(width 0)
					(fill yes)
				)
			)
		)
	)
	(footprint ""
		(layer "F.Cu")
		(at 192.9384 -20.9042 -90)
		(property "Reference" "R699"
			(at 0 0 270)
			(layer "F.SilkS")
			(hide yes)
			(effects
				(font
					(size 1.27 1.27)
				)
			)
		)
		(property "Value" "4K7R2F-GP"
			(at 0.064008 -3.993896 270)
			(unlocked yes)
			(layer "F.Fab")
			(hide yes)
			(effects
				(font
					(size 1.016 1.016)
					(thickness 0.1524)
				)
			)
		)
		(property "Device Type" "R402H16"
			(at 0.064008 -5.517896 270)
			(unlocked yes)
			(layer "F.Fab")
			(hide yes)
			(effects
				(font
					(size 1.016 1.016)
					(thickness 0.1524)
				)
			)
		)
		(duplicate_pad_numbers_are_jumpers no)
		(fp_line
			(start -0.508 -0.9398)
			(end -0.508 0.9398)
			(stroke
				(width 0.1524)
				(type default)
			)
			(layer "F.SilkS")
		)
		(fp_line
			(start 0.508 -0.9398)
			(end -0.508 -0.9398)
			(stroke
				(width 0.1524)
				(type default)
			)
			(layer "F.SilkS")
		)
		(fp_rect
			(start -0.508 0.9398)
			(end 0.508 -0.9398)
			(stroke
				(width 0)
				(type default)
			)
			(fill no)
			(layer "F.CrtYd")
		)
		(fp_rect
			(start -0.508 0.9398)
			(end 0.508 -0.9398)
			(stroke
				(width 0)
				(type default)
			)
			(fill no)
			(layer "F.Fab")
		)
		(pad "1" smd custom
			(at 0 -0.4445 270)
			(size 0.1397 0.1397)
			(layers "F.Cu" "F.Mask" "F.Paste")
			(net "MINISAS_CN15_B_I2C_INT#")
			(options
				(clearance outline)
				(anchor circle)
			)
			(primitives
				(gr_poly
					(pts
						(arc
							(start -0.1778 -0.2794)
							(mid -0.249642 -0.249642)
							(end -0.2794 -0.1778)
						)
						(arc
							(start -0.2794 0.1778)
							(mid -0.249642 0.249642)
							(end -0.1778 0.2794)
						)
						(arc
							(start 0.1778 0.2794)
							(mid 0.249642 0.249642)
							(end 0.2794 0.1778)
						)
						(arc
							(start 0.2794 -0.1778)
							(mid 0.249642 -0.249642)
							(end 0.1778 -0.2794)
						)
					)
					(width 0)
					(fill yes)
				)
			)
		)
		(pad "2" smd custom
			(at 0 0.4445 270)
			(size 0.1397 0.1397)
			(layers "F.Cu" "F.Mask" "F.Paste")
			(net "P3V3_STBY")
			(options
				(clearance outline)
				(anchor circle)
			)
			(primitives
				(gr_poly
					(pts
						(arc
							(start -0.1778 -0.2794)
							(mid -0.249642 -0.249642)
							(end -0.2794 -0.1778)
						)
						(arc
							(start -0.2794 0.1778)
							(mid -0.249642 0.249642)
							(end -0.1778 0.2794)
						)
						(arc
							(start 0.1778 0.2794)
							(mid 0.249642 0.249642)
							(end 0.2794 0.1778)
						)
						(arc
							(start 0.2794 -0.1778)
							(mid 0.249642 -0.249642)
							(end 0.1778 -0.2794)
						)
					)
					(width 0)
					(fill yes)
				)
			)
		)
	)
	(footprint ""
		(layer "F.Cu")
		(at 232.537 -23.241)
		(property "Reference" "R818"
			(at 0 0 0)
			(layer "F.SilkS")
			(hide yes)
			(effects
				(font
					(size 1.27 1.27)
				)
			)
		)
		(property "Value" "4K7R2F-GP"
			(at 0.064008 -3.993896 0)
			(unlocked yes)
			(layer "F.Fab")
			(hide yes)
			(effects
				(font
					(size 1.016 1.016)
					(thickness 0.1524)
				)
			)
		)
		(property "Device Type" "R402H16"
			(at 0.064008 -5.517896 0)
			(unlocked yes)
			(layer "F.Fab")
			(hide yes)
			(effects
				(font
					(size 1.016 1.016)
					(thickness 0.1524)
				)
			)
		)
		(duplicate_pad_numbers_are_jumpers no)
		(fp_line
			(start -0.508 -0.9398)
			(end -0.508 0.9398)
			(stroke
				(width 0.1524)
				(type default)
			)
			(layer "F.SilkS")
		)
		(fp_line
			(start 0.508 -0.9398)
			(end -0.508 -0.9398)
			(stroke
				(width 0.1524)
				(type default)
			)
			(layer "F.SilkS")
		)
		(fp_rect
			(start -0.508 0.9398)
			(end 0.508 -0.9398)
			(stroke
				(width 0)
				(type default)
			)
			(fill no)
			(layer "F.CrtYd")
		)
		(fp_rect
			(start -0.508 0.9398)
			(end 0.508 -0.9398)
			(stroke
				(width 0)
				(type default)
			)
			(fill no)
			(layer "F.Fab")
		)
		(pad "1" smd custom
			(at 0 -0.4445)
			(size 0.1397 0.1397)
			(layers "F.Cu" "F.Mask" "F.Paste")
			(net "GND")
			(options
				(clearance outline)
				(anchor circle)
			)
			(primitives
				(gr_poly
					(pts
						(arc
							(start -0.1778 -0.2794)
							(mid -0.249642 -0.249642)
							(end -0.2794 -0.1778)
						)
						(arc
							(start -0.2794 0.1778)
							(mid -0.249642 0.249642)
							(end -0.1778 0.2794)
						)
						(arc
							(start 0.1778 0.2794)
							(mid 0.249642 0.249642)
							(end 0.2794 0.1778)
						)
						(arc
							(start 0.2794 -0.1778)
							(mid 0.249642 -0.249642)
							(end 0.1778 -0.2794)
						)
					)
					(width 0)
					(fill yes)
				)
			)
		)
		(pad "2" smd custom
			(at 0 0.4445)
			(size 0.1397 0.1397)
			(layers "F.Cu" "F.Mask" "F.Paste")
			(net "BOOTSTRAP9")
			(options
				(clearance outline)
				(anchor circle)
			)
			(primitives
				(gr_poly
					(pts
						(arc
							(start -0.1778 -0.2794)
							(mid -0.249642 -0.249642)
							(end -0.2794 -0.1778)
						)
						(arc
							(start -0.2794 0.1778)
							(mid -0.249642 0.249642)
							(end -0.1778 0.2794)
						)
						(arc
							(start 0.1778 0.2794)
							(mid 0.249642 0.249642)
							(end 0.2794 0.1778)
						)
						(arc
							(start 0.2794 -0.1778)
							(mid 0.249642 -0.249642)
							(end 0.1778 -0.2794)
						)
					)
					(width 0)
					(fill yes)
				)
			)
		)
	)
	(footprint ""
		(layer "F.Cu")
		(at 225.9076 -13.081 90)
		(property "Reference" "C374"
			(at 0 0 90)
			(layer "F.SilkS")
			(hide yes)
			(effects
				(font
					(size 1.27 1.27)
				)
			)
		)
		(property "Value" "SCD1U25V2KX-2-GP"
			(at 1.1811 -2.7051 90)
			(unlocked yes)
			(layer "F.Fab")
			(hide yes)
			(effects
				(font
					(size 1.016 1.016)
					(thickness 0.1524)
				)
			)
		)
		(property "Device Type" "C402H22"
			(at 1.1811 -4.2291 90)
			(unlocked yes)
			(layer "F.Fab")
			(hide yes)
			(effects
				(font
					(size 1.016 1.016)
					(thickness 0.1524)
				)
			)
		)
		(duplicate_pad_numbers_are_jumpers no)
		(fp_rect
			(start -0.4318 0.9525)
			(end 0.4318 -0.9525)
			(stroke
				(width 0)
				(type default)
			)
			(fill no)
			(layer "F.CrtYd")
		)
		(fp_rect
			(start -0.4318 0.9525)
			(end 0.4318 -0.9525)
			(stroke
				(width 0)
				(type default)
			)
			(fill no)
			(layer "F.Fab")
		)
		(pad "1" smd custom
			(at 0 -0.4445 90)
			(size 0.1524 0.1524)
			(layers "F.Cu" "F.Mask" "F.Paste")
			(net "P3V3_STBY")
			(options
				(clearance outline)
				(anchor circle)
			)
			(primitives
				(gr_poly
					(pts
						(arc
							(start 0.3048 -0.2032)
							(mid 0.275042 -0.275042)
							(end 0.2032 -0.3048)
						)
						(arc
							(start -0.2032 -0.3048)
							(mid -0.275042 -0.275042)
							(end -0.3048 -0.2032)
						)
						(arc
							(start -0.3048 0.2032)
							(mid -0.275042 0.275042)
							(end -0.2032 0.3048)
						)
						(arc
							(start 0.2032 0.3048)
							(mid 0.275042 0.275042)
							(end 0.3048 0.2032)
						)
					)
					(width 0)
					(fill yes)
				)
			)
		)
		(pad "2" smd custom
			(at 0 0.4445 90)
			(size 0.1524 0.1524)
			(layers "F.Cu" "F.Mask" "F.Paste")
			(net "GND")
			(options
				(clearance outline)
				(anchor circle)
			)
			(primitives
				(gr_poly
					(pts
						(arc
							(start 0.3048 -0.2032)
							(mid 0.275042 -0.275042)
							(end 0.2032 -0.3048)
						)
						(arc
							(start -0.2032 -0.3048)
							(mid -0.275042 -0.275042)
							(end -0.3048 -0.2032)
						)
						(arc
							(start -0.3048 0.2032)
							(mid -0.275042 0.275042)
							(end -0.2032 0.3048)
						)
						(arc
							(start 0.2032 0.3048)
							(mid 0.275042 0.275042)
							(end 0.3048 0.2032)
						)
					)
					(width 0)
					(fill yes)
				)
			)
		)
	)
)
